(kicad_pcb
	(version 20260206)
	(generator "pcbnew")
	(generator_version "10.0")
	(general
		(thickness 1.6)
		(legacy_teardrops no)
	)
	(paper "A4")
	(title_block
		(title "peb — Lightning_PEB_BRD.brd")
		(comment 1 "Lightning (Wiwynn / Facebook NVMe JBOF) / footprints 1079-1085 of 2563")
	)
	(layers
		(0 "F.Cu" signal "TOP")
		(4 "In1.Cu" signal "L2GND")
		(6 "In2.Cu" signal "L3")
		(8 "In3.Cu" signal "L4VCC")
		(10 "In4.Cu" signal "L5VCC")
		(12 "In5.Cu" signal "L6")
		(14 "In6.Cu" signal "L7GND")
		(2 "B.Cu" signal "BOTTOM")
		(9 "F.Adhes" user "F.Adhesive")
		(11 "B.Adhes" user "B.Adhesive")
		(13 "F.Paste" user "Package Geometry/Pastemask Top")
		(15 "B.Paste" user "Package Geometry/Pastemask Bottom")
		(5 "F.SilkS" user "Ref Des/Silkscreen Top")
		(7 "B.SilkS" user "Ref Des/Silkscreen Bottom")
		(1 "F.Mask" user "Board Geometry/Soldermask Top")
		(3 "B.Mask" user "Board Geometry/Soldermask Bottom")
		(17 "Dwgs.User" user "User.Drawings")
		(19 "Cmts.User" user "User.Comments")
		(21 "Eco1.User" user "User.Eco1")
		(23 "Eco2.User" user "User.Eco2")
		(25 "Edge.Cuts" user "Board Geometry/Outline")
		(27 "Margin" user)
		(31 "F.CrtYd" user "Package Geometry/Place Bound Top")
		(29 "B.CrtYd" user "Package Geometry/Place Bound Bottom")
		(35 "F.Fab" user "Ref Des/Assembly Top")
		(33 "B.Fab" user "Ref Des/Assembly Bottom")
	)
	(footprint ""
		(layer "F.Cu")
		(at 143.982186 -79.309214)
		(property "Reference" "PL10"
			(at 0 0 0)
			(layer "F.SilkS")
			(hide yes)
			(effects
				(font
					(size 1.27 1.27)
				)
			)
		)
		(property "Value" "BLM41PG600-GP"
			(at -3.690874 -7.441184 0)
			(unlocked yes)
			(layer "F.Fab")
			(hide yes)
			(effects
				(font
					(size 1.016 1.016)
					(thickness 0.1524)
				)
			)
		)
		(property "Device Type" "L451616H71"
			(at -3.690874 -5.917184 0)
			(unlocked yes)
			(layer "F.Fab")
			(hide yes)
			(effects
				(font
					(size 1.016 1.016)
					(thickness 0.1524)
				)
			)
		)
		(duplicate_pad_numbers_are_jumpers no)
		(fp_line
			(start -2.8702 -1.2954)
			(end -2.8702 1.2954)
			(stroke
				(width 0.1524)
				(type default)
			)
			(layer "F.SilkS")
		)
		(fp_line
			(start -2.8702 -1.2954)
			(end -2.8702 1.2954)
			(stroke
				(width 0.1524)
				(type default)
			)
			(layer "F.SilkS")
		)
		(fp_line
			(start -2.8702 1.2954)
			(end 2.8702 1.2954)
			(stroke
				(width 0.1524)
				(type default)
			)
			(layer "F.SilkS")
		)
		(fp_line
			(start -2.8702 1.2954)
			(end 2.8702 1.2954)
			(stroke
				(width 0.1524)
				(type default)
			)
			(layer "F.SilkS")
		)
		(fp_line
			(start 2.8702 -1.2954)
			(end -2.8702 -1.2954)
			(stroke
				(width 0.1524)
				(type default)
			)
			(layer "F.SilkS")
		)
		(fp_line
			(start 2.8702 -1.2954)
			(end -2.8702 -1.2954)
			(stroke
				(width 0.1524)
				(type default)
			)
			(layer "F.SilkS")
		)
		(fp_line
			(start 2.8702 1.2954)
			(end 2.8702 -1.2954)
			(stroke
				(width 0.1524)
				(type default)
			)
			(layer "F.SilkS")
		)
		(fp_line
			(start 2.8702 1.2954)
			(end 2.8702 -1.2954)
			(stroke
				(width 0.1524)
				(type default)
			)
			(layer "F.SilkS")
		)
		(fp_poly
			(pts
				(xy -2.8702 1.2954) (xy 2.8702 1.2954) (xy 2.8702 -1.2954) (xy -2.8702 -1.2954)
			)
			(stroke
				(width 0)
				(type default)
			)
			(fill no)
			(layer "F.CrtYd")
		)
		(fp_poly
			(pts
				(xy -2.8702 1.2954) (xy 2.8702 1.2954) (xy 2.8702 -1.2954) (xy -2.8702 -1.2954)
			)
			(stroke
				(width 0)
				(type default)
			)
			(fill no)
			(layer "F.Fab")
		)
		(pad "1" smd rect
			(at -1.9685 0)
			(size 1.3716 1.8796)
			(layers "F.Cu" "F.Mask" "F.Paste")
			(net "P12V")
		)
		(pad "2" smd rect
			(at 1.9685 0)
			(size 1.3716 1.8796)
			(layers "F.Cu" "F.Mask" "F.Paste")
			(net "P0V9_VIN")
		)
	)
	(footprint ""
		(layer "F.Cu")
		(at 281.408124 -212.420454 180)
		(property "Reference" "C96"
			(at 0 0 180)
			(layer "F.SilkS")
			(hide yes)
			(effects
				(font
					(size 1.27 1.27)
				)
			)
		)
		(property "Value" "SCD22U10V2KX-1GP"
			(at 1.1811 -2.7051 180)
			(unlocked yes)
			(layer "F.Fab")
			(hide yes)
			(effects
				(font
					(size 1.016 1.016)
					(thickness 0.1524)
				)
			)
		)
		(property "Device Type" "C402H22"
			(at 1.1811 -4.2291 180)
			(unlocked yes)
			(layer "F.Fab")
			(hide yes)
			(effects
				(font
					(size 1.016 1.016)
					(thickness 0.1524)
				)
			)
		)
		(duplicate_pad_numbers_are_jumpers no)
		(fp_rect
			(start -0.4318 0.9525)
			(end 0.4318 -0.9525)
			(stroke
				(width 0)
				(type default)
			)
			(fill no)
			(layer "F.CrtYd")
		)
		(fp_rect
			(start -0.4318 0.9525)
			(end 0.4318 -0.9525)
			(stroke
				(width 0)
				(type default)
			)
			(fill no)
			(layer "F.Fab")
		)
		(pad "1" smd custom
			(at 0 -0.4445 180)
			(size 0.1524 0.1524)
			(layers "F.Cu" "F.Mask" "F.Paste")
			(net "PCIE_TX_CAP_N32")
			(options
				(clearance outline)
				(anchor circle)
			)
			(primitives
				(gr_poly
					(pts
						(arc
							(start 0.3048 -0.2032)
							(mid 0.275042 -0.275042)
							(end 0.2032 -0.3048)
						)
						(arc
							(start -0.2032 -0.3048)
							(mid -0.275042 -0.275042)
							(end -0.3048 -0.2032)
						)
						(arc
							(start -0.3048 0.2032)
							(mid -0.275042 0.275042)
							(end -0.2032 0.3048)
						)
						(arc
							(start 0.2032 0.3048)
							(mid 0.275042 0.275042)
							(end 0.3048 0.2032)
						)
					)
					(width 0)
					(fill yes)
				)
			)
		)
		(pad "2" smd custom
			(at 0 0.4445 180)
			(size 0.1524 0.1524)
			(layers "F.Cu" "F.Mask" "F.Paste")
			(net "PCIE_TX_N32")
			(options
				(clearance outline)
				(anchor circle)
			)
			(primitives
				(gr_poly
					(pts
						(arc
							(start 0.3048 -0.2032)
							(mid 0.275042 -0.275042)
							(end 0.2032 -0.3048)
						)
						(arc
							(start -0.2032 -0.3048)
							(mid -0.275042 -0.275042)
							(end -0.3048 -0.2032)
						)
						(arc
							(start -0.3048 0.2032)
							(mid -0.275042 0.275042)
							(end -0.2032 0.3048)
						)
						(arc
							(start 0.2032 0.3048)
							(mid 0.275042 0.275042)
							(end 0.3048 0.2032)
						)
					)
					(width 0)
					(fill yes)
				)
			)
		)
	)
	(footprint ""
		(layer "F.Cu")
		(at 251.680726 -5.872734 -90)
		(property "Reference" "R269"
			(at 0 0 270)
			(layer "F.SilkS")
			(hide yes)
			(effects
				(font
					(size 1.27 1.27)
				)
			)
		)
		(property "Value" "0R2J-2-GP"
			(at 0.064008 -3.993896 270)
			(unlocked yes)
			(layer "F.Fab")
			(hide yes)
			(effects
				(font
					(size 1.016 1.016)
					(thickness 0.1524)
				)
			)
		)
		(property "Device Type" "R402H16"
			(at 0.064008 -5.517896 270)
			(unlocked yes)
			(layer "F.Fab")
			(hide yes)
			(effects
				(font
					(size 1.016 1.016)
					(thickness 0.1524)
				)
			)
		)
		(duplicate_pad_numbers_are_jumpers no)
		(fp_line
			(start -0.508 -0.9398)
			(end -0.508 0.9398)
			(stroke
				(width 0.1524)
				(type default)
			)
			(layer "F.SilkS")
		)
		(fp_line
			(start 0.508 -0.9398)
			(end -0.508 -0.9398)
			(stroke
				(width 0.1524)
				(type default)
			)
			(layer "F.SilkS")
		)
		(fp_rect
			(start -0.508 0.9398)
			(end 0.508 -0.9398)
			(stroke
				(width 0)
				(type default)
			)
			(fill no)
			(layer "F.CrtYd")
		)
		(fp_rect
			(start -0.508 0.9398)
			(end 0.508 -0.9398)
			(stroke
				(width 0)
				(type default)
			)
			(fill no)
			(layer "F.Fab")
		)
		(pad "1" smd custom
			(at 0 -0.4445 270)
			(size 0.1397 0.1397)
			(layers "F.Cu" "F.Mask" "F.Paste")
			(net "I2C_MAX6654_DAT")
			(options
				(clearance outline)
				(anchor circle)
			)
			(primitives
				(gr_poly
					(pts
						(arc
							(start -0.1778 -0.2794)
							(mid -0.249642 -0.249642)
							(end -0.2794 -0.1778)
						)
						(arc
							(start -0.2794 0.1778)
							(mid -0.249642 0.249642)
							(end -0.1778 0.2794)
						)
						(arc
							(start 0.1778 0.2794)
							(mid 0.249642 0.249642)
							(end 0.2794 0.1778)
						)
						(arc
							(start 0.2794 -0.1778)
							(mid 0.249642 -0.249642)
							(end 0.1778 -0.2794)
						)
					)
					(width 0)
					(fill yes)
				)
			)
		)
		(pad "2" smd custom
			(at 0 0.4445 270)
			(size 0.1397 0.1397)
			(layers "F.Cu" "F.Mask" "F.Paste")
			(net "BMC_I2C5_D_PEB_SDA")
			(options
				(clearance outline)
				(anchor circle)
			)
			(primitives
				(gr_poly
					(pts
						(arc
							(start -0.1778 -0.2794)
							(mid -0.249642 -0.249642)
							(end -0.2794 -0.1778)
						)
						(arc
							(start -0.2794 0.1778)
							(mid -0.249642 0.249642)
							(end -0.1778 0.2794)
						)
						(arc
							(start 0.1778 0.2794)
							(mid 0.249642 0.249642)
							(end 0.2794 0.1778)
						)
						(arc
							(start 0.2794 -0.1778)
							(mid 0.249642 -0.249642)
							(end 0.1778 -0.2794)
						)
					)
					(width 0)
					(fill yes)
				)
			)
		)
	)
	(footprint ""
		(layer "F.Cu")
		(at 5.969 -107.696 90)
		(property "Reference" "PR71"
			(at 0 0 90)
			(layer "F.SilkS")
			(hide yes)
			(effects
				(font
					(size 1.27 1.27)
				)
			)
		)
		(property "Value" "0R2J-2-GP"
			(at 0.064008 -3.993896 90)
			(unlocked yes)
			(layer "F.Fab")
			(hide yes)
			(effects
				(font
					(size 1.016 1.016)
					(thickness 0.1524)
				)
			)
		)
		(property "Device Type" "R402H16"
			(at 0.064008 -5.517896 90)
			(unlocked yes)
			(layer "F.Fab")
			(hide yes)
			(effects
				(font
					(size 1.016 1.016)
					(thickness 0.1524)
				)
			)
		)
		(duplicate_pad_numbers_are_jumpers no)
		(fp_line
			(start 0.508 -0.9398)
			(end -0.508 -0.9398)
			(stroke
				(width 0.1524)
				(type default)
			)
			(layer "F.SilkS")
		)
		(fp_line
			(start -0.508 -0.9398)
			(end -0.508 0.9398)
			(stroke
				(width 0.1524)
				(type default)
			)
			(layer "F.SilkS")
		)
		(fp_rect
			(start -0.508 0.9398)
			(end 0.508 -0.9398)
			(stroke
				(width 0)
				(type default)
			)
			(fill no)
			(layer "F.CrtYd")
		)
		(fp_rect
			(start -0.508 0.9398)
			(end 0.508 -0.9398)
			(stroke
				(width 0)
				(type default)
			)
			(fill no)
			(layer "F.Fab")
		)
		(pad "1" smd custom
			(at 0 -0.4445 90)
			(size 0.1397 0.1397)
			(layers "F.Cu" "F.Mask" "F.Paste")
			(net "P5V_STBY")
			(options
				(clearance outline)
				(anchor circle)
			)
			(primitives
				(gr_poly
					(pts
						(arc
							(start -0.1778 -0.2794)
							(mid -0.249642 -0.249642)
							(end -0.2794 -0.1778)
						)
						(arc
							(start -0.2794 0.1778)
							(mid -0.249642 0.249642)
							(end -0.1778 0.2794)
						)
						(arc
							(start 0.1778 0.2794)
							(mid 0.249642 0.249642)
							(end 0.2794 0.1778)
						)
						(arc
							(start 0.2794 -0.1778)
							(mid 0.249642 -0.249642)
							(end 0.1778 -0.2794)
						)
					)
					(width 0)
					(fill yes)
				)
			)
		)
		(pad "2" smd custom
			(at 0 0.4445 90)
			(size 0.1397 0.1397)
			(layers "F.Cu" "F.Mask" "F.Paste")
			(net "VR_P1V26_STBY_BIAS")
			(options
				(clearance outline)
				(anchor circle)
			)
			(primitives
				(gr_poly
					(pts
						(arc
							(start -0.1778 -0.2794)
							(mid -0.249642 -0.249642)
							(end -0.2794 -0.1778)
						)
						(arc
							(start -0.2794 0.1778)
							(mid -0.249642 0.249642)
							(end -0.1778 0.2794)
						)
						(arc
							(start 0.1778 0.2794)
							(mid 0.249642 0.249642)
							(end 0.2794 0.1778)
						)
						(arc
							(start 0.2794 -0.1778)
							(mid 0.249642 -0.249642)
							(end 0.1778 -0.2794)
						)
					)
					(width 0)
					(fill yes)
				)
			)
		)
	)
	(footprint ""
		(layer "F.Cu")
		(at 57.0484 -30.9372)
		(property "Reference" "R570"
			(at 0 0 0)
			(layer "F.SilkS")
			(hide yes)
			(effects
				(font
					(size 1.27 1.27)
				)
			)
		)
		(property "Value" "10KR2F-2-GP"
			(at 0.064008 -3.993896 0)
			(unlocked yes)
			(layer "F.Fab")
			(hide yes)
			(effects
				(font
					(size 1.016 1.016)
					(thickness 0.1524)
				)
			)
		)
		(property "Device Type" "R402H16"
			(at 0.064008 -5.517896 0)
			(unlocked yes)
			(layer "F.Fab")
			(hide yes)
			(effects
				(font
					(size 1.016 1.016)
					(thickness 0.1524)
				)
			)
		)
		(duplicate_pad_numbers_are_jumpers no)
		(fp_line
			(start -0.508 -0.9398)
			(end -0.508 0.9398)
			(stroke
				(width 0.1524)
				(type default)
			)
			(layer "F.SilkS")
		)
		(fp_line
			(start 0.508 -0.9398)
			(end -0.508 -0.9398)
			(stroke
				(width 0.1524)
				(type default)
			)
			(layer "F.SilkS")
		)
		(fp_rect
			(start -0.508 0.9398)
			(end 0.508 -0.9398)
			(stroke
				(width 0)
				(type default)
			)
			(fill no)
			(layer "F.CrtYd")
		)
		(fp_rect
			(start -0.508 0.9398)
			(end 0.508 -0.9398)
			(stroke
				(width 0)
				(type default)
			)
			(fill no)
			(layer "F.Fab")
		)
		(pad "1" smd custom
			(at 0 -0.4445)
			(size 0.1397 0.1397)
			(layers "F.Cu" "F.Mask" "F.Paste")
			(net "P3V3_STBY")
			(options
				(clearance outline)
				(anchor circle)
			)
			(primitives
				(gr_poly
					(pts
						(arc
							(start -0.1778 -0.2794)
							(mid -0.249642 -0.249642)
							(end -0.2794 -0.1778)
						)
						(arc
							(start -0.2794 0.1778)
							(mid -0.249642 0.249642)
							(end -0.1778 0.2794)
						)
						(arc
							(start 0.1778 0.2794)
							(mid 0.249642 0.249642)
							(end 0.2794 0.1778)
						)
						(arc
							(start 0.2794 -0.1778)
							(mid 0.249642 -0.249642)
							(end 0.1778 -0.2794)
						)
					)
					(width 0)
					(fill yes)
				)
			)
		)
		(pad "2" smd custom
			(at 0 0.4445)
			(size 0.1397 0.1397)
			(layers "F.Cu" "F.Mask" "F.Paste")
			(net "TRAY_POWER_CRIT_N")
			(options
				(clearance outline)
				(anchor circle)
			)
			(primitives
				(gr_poly
					(pts
						(arc
							(start -0.1778 -0.2794)
							(mid -0.249642 -0.249642)
							(end -0.2794 -0.1778)
						)
						(arc
							(start -0.2794 0.1778)
							(mid -0.249642 0.249642)
							(end -0.1778 0.2794)
						)
						(arc
							(start 0.1778 0.2794)
							(mid 0.249642 0.249642)
							(end 0.2794 0.1778)
						)
						(arc
							(start 0.2794 -0.1778)
							(mid 0.249642 -0.249642)
							(end 0.1778 -0.2794)
						)
					)
					(width 0)
					(fill yes)
				)
			)
		)
	)
	(footprint ""
		(layer "F.Cu")
		(at 24.30018 -86.997794)
		(property "Reference" "R405"
			(at 0 0 0)
			(layer "F.SilkS")
			(hide yes)
			(effects
				(font
					(size 1.27 1.27)
				)
			)
		)
		(property "Value" "3K3R2F-2-GP"
			(at 0.064008 -3.993896 0)
			(unlocked yes)
			(layer "F.Fab")
			(hide yes)
			(effects
				(font
					(size 1.016 1.016)
					(thickness 0.1524)
				)
			)
		)
		(property "Device Type" "R402H16"
			(at 0.064008 -5.517896 0)
			(unlocked yes)
			(layer "F.Fab")
			(hide yes)
			(effects
				(font
					(size 1.016 1.016)
					(thickness 0.1524)
				)
			)
		)
		(duplicate_pad_numbers_are_jumpers no)
		(fp_line
			(start -0.508 -0.9398)
			(end -0.508 0.9398)
			(stroke
				(width 0.1524)
				(type default)
			)
			(layer "F.SilkS")
		)
		(fp_line
			(start 0.508 -0.9398)
			(end -0.508 -0.9398)
			(stroke
				(width 0.1524)
				(type default)
			)
			(layer "F.SilkS")
		)
		(fp_rect
			(start -0.508 0.9398)
			(end 0.508 -0.9398)
			(stroke
				(width 0)
				(type default)
			)
			(fill no)
			(layer "F.CrtYd")
		)
		(fp_rect
			(start -0.508 0.9398)
			(end 0.508 -0.9398)
			(stroke
				(width 0)
				(type default)
			)
			(fill no)
			(layer "F.Fab")
		)
		(pad "1" smd custom
			(at 0 -0.4445)
			(size 0.1397 0.1397)
			(layers "F.Cu" "F.Mask" "F.Paste")
			(net "P3V3_STBY")
			(options
				(clearance outline)
				(anchor circle)
			)
			(primitives
				(gr_poly
					(pts
						(arc
							(start -0.1778 -0.2794)
							(mid -0.249642 -0.249642)
							(end -0.2794 -0.1778)
						)
						(arc
							(start -0.2794 0.1778)
							(mid -0.249642 0.249642)
							(end -0.1778 0.2794)
						)
						(arc
							(start 0.1778 0.2794)
							(mid 0.249642 0.249642)
							(end 0.2794 0.1778)
						)
						(arc
							(start 0.2794 -0.1778)
							(mid 0.249642 -0.249642)
							(end 0.1778 -0.2794)
						)
					)
					(width 0)
					(fill yes)
				)
			)
		)
		(pad "2" smd custom
			(at 0 0.4445)
			(size 0.1397 0.1397)
			(layers "F.Cu" "F.Mask" "F.Paste")
			(net "NIC_JTMS")
			(options
				(clearance outline)
				(anchor circle)
			)
			(primitives
				(gr_poly
					(pts
						(arc
							(start -0.1778 -0.2794)
							(mid -0.249642 -0.249642)
							(end -0.2794 -0.1778)
						)
						(arc
							(start -0.2794 0.1778)
							(mid -0.249642 0.249642)
							(end -0.1778 0.2794)
						)
						(arc
							(start 0.1778 0.2794)
							(mid 0.249642 0.249642)
							(end 0.2794 0.1778)
						)
						(arc
							(start 0.2794 -0.1778)
							(mid 0.249642 -0.249642)
							(end 0.1778 -0.2794)
						)
					)
					(width 0)
					(fill yes)
				)
			)
		)
	)
	(footprint ""
		(layer "F.Cu")
		(at 256.711704 -10.988548)
		(property "Reference" "R4"
			(at 0 0 0)
			(layer "F.SilkS")
			(hide yes)
			(effects
				(font
					(size 1.27 1.27)
				)
			)
		)
		(property "Value" "0R2J-2-GP"
			(at 0.064008 -3.993896 0)
			(unlocked yes)
			(layer "F.Fab")
			(hide yes)
			(effects
				(font
					(size 1.016 1.016)
					(thickness 0.1524)
				)
			)
		)
		(property "Device Type" "R402H16"
			(at 0.064008 -5.517896 0)
			(unlocked yes)
			(layer "F.Fab")
			(hide yes)
			(effects
				(font
					(size 1.016 1.016)
					(thickness 0.1524)
				)
			)
		)
		(duplicate_pad_numbers_are_jumpers no)
		(fp_line
			(start -0.508 -0.9398)
			(end -0.508 0.9398)
			(stroke
				(width 0.1524)
				(type default)
			)
			(layer "F.SilkS")
		)
		(fp_line
			(start 0.508 -0.9398)
			(end -0.508 -0.9398)
			(stroke
				(width 0.1524)
				(type default)
			)
			(layer "F.SilkS")
		)
		(fp_rect
			(start -0.508 0.9398)
			(end 0.508 -0.9398)
			(stroke
				(width 0)
				(type default)
			)
			(fill no)
			(layer "F.CrtYd")
		)
		(fp_rect
			(start -0.508 0.9398)
			(end 0.508 -0.9398)
			(stroke
				(width 0)
				(type default)
			)
			(fill no)
			(layer "F.Fab")
		)
		(pad "1" smd custom
			(at 0 -0.4445)
			(size 0.1397 0.1397)
			(layers "F.Cu" "F.Mask" "F.Paste")
			(net "THERM_EMIT")
			(options
				(clearance outline)
				(anchor circle)
			)
			(primitives
				(gr_poly
					(pts
						(arc
							(start -0.1778 -0.2794)
							(mid -0.249642 -0.249642)
							(end -0.2794 -0.1778)
						)
						(arc
							(start -0.2794 0.1778)
							(mid -0.249642 0.249642)
							(end -0.1778 0.2794)
						)
						(arc
							(start 0.1778 0.2794)
							(mid 0.249642 0.249642)
							(end 0.2794 0.1778)
						)
						(arc
							(start 0.2794 -0.1778)
							(mid 0.249642 -0.249642)
							(end 0.1778 -0.2794)
						)
					)
					(width 0)
					(fill yes)
				)
			)
		)
		(pad "2" smd custom
			(at 0 0.4445)
			(size 0.1397 0.1397)
			(layers "F.Cu" "F.Mask" "F.Paste")
			(net "THERM_EMIT_R")
			(options
				(clearance outline)
				(anchor circle)
			)
			(primitives
				(gr_poly
					(pts
						(arc
							(start -0.1778 -0.2794)
							(mid -0.249642 -0.249642)
							(end -0.2794 -0.1778)
						)
						(arc
							(start -0.2794 0.1778)
							(mid -0.249642 0.249642)
							(end -0.1778 0.2794)
						)
						(arc
							(start 0.1778 0.2794)
							(mid 0.249642 0.249642)
							(end 0.2794 0.1778)
						)
						(arc
							(start 0.2794 -0.1778)
							(mid 0.249642 -0.249642)
							(end 0.1778 -0.2794)
						)
					)
					(width 0)
					(fill yes)
				)
			)
		)
	)
)
